# T6G (Grand Teton) — schematic netlist excerpt (pin names and nets, part order shuffled) for the footprints in the layout excerpt that follows; sources: Cadence DE-HDL packaged netlist, KiCad conversion of 04192023_DAF0TMB3IC0_F0TG_MB_C_brd_V02_OCP.brd

C358  Q_CAP  0.1UF 16V 10% X7R  pkg C0402  page 83 : A = P3V3_AUX ; B = GND
R2414  Q_RES  33.2 1% CHIP  pkg 0402LF  page 150 : A = SMB_2_BMC_GPU_SDA ; B = SMB_PCIE2_3V3AUX_SDA_R0

(kicad_pcb
	(version 20260206)
	(generator "pcbnew")
	(generator_version "10.0")
	(general
		(thickness 1.6)
		(legacy_teardrops no)
	)
	(paper "A4")
	(title_block
		(title "04192023_DAF0TMB3IC0_F0TG_MB_C_brd_V02_OCP.brd")
		(comment 1 "Grand Teton / footprints 7156-7157 of 8354")
	)
	(layers
		(0 "F.Cu" signal "TOP")
		(4 "In1.Cu" signal "GND")
		(6 "In2.Cu" signal "IN1")
		(8 "In3.Cu" signal "GND1")
		(10 "In4.Cu" signal "IN2")
		(12 "In5.Cu" signal "GND2")
		(14 "In6.Cu" signal "IN3")
		(16 "In7.Cu" signal "GND3")
		(18 "In8.Cu" signal "VCC")
		(20 "In9.Cu" signal "VCC1")
		(22 "In10.Cu" signal "GND4")
		(24 "In11.Cu" signal "IN4")
		(26 "In12.Cu" signal "GND5")
		(28 "In13.Cu" signal "IN5")
		(30 "In14.Cu" signal "GND6")
		(32 "In15.Cu" signal "IN6")
		(34 "In16.Cu" signal "GND7")
		(2 "B.Cu" signal "BOTTOM")
		(9 "F.Adhes" user "F.Adhesive")
		(11 "B.Adhes" user "B.Adhesive")
		(13 "F.Paste" user "Package Geometry/Pastemask Top")
		(15 "B.Paste" user "Package Geometry/Pastemask Bottom")
		(5 "F.SilkS" user "Ref Des/Silkscreen Top")
		(7 "B.SilkS" user "Ref Des/Silkscreen Bottom")
		(1 "F.Mask" user "Board Geometry/Soldermask Top")
		(3 "B.Mask" user "Board Geometry/Soldermask Bottom")
		(17 "Dwgs.User" user "User.Drawings")
		(19 "Cmts.User" user "User.Comments")
		(21 "Eco1.User" user "User.Eco1")
		(23 "Eco2.User" user "User.Eco2")
		(25 "Edge.Cuts" user "Board Geometry/Outline")
		(27 "Margin" user)
		(31 "F.CrtYd" user "Package Geometry/Place Bound Top")
		(29 "B.CrtYd" user "Package Geometry/Place Bound Bottom")
		(35 "F.Fab" user "Ref Des/Assembly Top")
		(33 "B.Fab" user "Ref Des/Assembly Bottom")
	)
	(footprint ""
		(layer "B.Cu")
		(at 186.711844 -113.462816 90)
		(property "Reference" "C358"
			(at 0 0 90)
			(layer "B.SilkS")
			(hide yes)
			(effects
				(font
					(size 1.27 1.27)
				)
				(justify mirror)
			)
		)
		(property "Value" ""
			(at 0 0 90)
			(layer "B.Fab")
			(effects
				(font
					(size 1.27 1.27)
				)
				(justify mirror)
			)
		)
		(duplicate_pad_numbers_are_jumpers no)
		(fp_line
			(start 0.69215 -0.2921)
			(end -0.69215 -0.2921)
			(stroke
				(width 0.1524)
				(type default)
			)
			(layer "B.SilkS")
		)
		(fp_line
			(start -0.69215 -0.2921)
			(end -0.69215 0.2921)
			(stroke
				(width 0.1524)
				(type default)
			)
			(layer "B.SilkS")
		)
		(fp_line
			(start 0.69215 0.2921)
			(end 0.69215 -0.2921)
			(stroke
				(width 0.1524)
				(type default)
			)
			(layer "B.SilkS")
		)
		(fp_line
			(start -0.69215 0.2921)
			(end 0.69215 0.2921)
			(stroke
				(width 0.1524)
				(type default)
			)
			(layer "B.SilkS")
		)
		(fp_line
			(start 0.51435 -0.2794)
			(end -0.51435 -0.2794)
			(stroke
				(width 0.1)
				(type default)
			)
			(layer "B.Fab")
		)
		(fp_line
			(start -0.51435 -0.2794)
			(end -0.51435 0.2794)
			(stroke
				(width 0.1)
				(type default)
			)
			(layer "B.Fab")
		)
		(fp_line
			(start 0.51435 0.2794)
			(end 0.51435 -0.2794)
			(stroke
				(width 0.1)
				(type default)
			)
			(layer "B.Fab")
		)
		(fp_line
			(start -0.51435 0.2794)
			(end 0.51435 0.2794)
			(stroke
				(width 0.1)
				(type default)
			)
			(layer "B.Fab")
		)
		(pad "1" smd circle
			(at 0.40005 0 270)
			(size 0 0)
			(layers "B.Cu" "B.Mask" "B.Paste")
			(net "P3V3_AUX")
		)
		(pad "2" smd circle
			(at -0.40005 0 270)
			(size 0 0)
			(layers "B.Cu" "B.Mask" "B.Paste")
			(net "GND")
		)
		(zone
			(layer "B.Cu")
			(hatch none 0.5)
			(connect_pads
				(clearance 0)
			)
			(min_thickness 0.25)
			(keepout
				(tracks not_allowed)
				(vias allowed)
				(pads allowed)
				(copperpour not_allowed)
				(footprints allowed)
			)
			(placement
				(enabled no)
				(sheetname "")
			)
			(fill
				(thermal_gap 0.5)
				(thermal_bridge_width 0.5)
				(island_removal_mode 0)
			)
			(polygon
				(pts
					(xy 186.565794 -113.362486) (xy 186.565794 -113.561876) (xy 186.62396 -113.653316) (xy 186.799474 -113.653316)
					(xy 186.85764 -113.561876) (xy 186.85764 -113.362486) (xy 186.799474 -113.272316) (xy 186.624214 -113.272316)
				)
			)
		)
	)
	(footprint ""
		(layer "B.Cu")
		(at 155.01239 -13.762228 90)
		(property "Reference" "R2414"
			(at 0 0 90)
			(layer "B.SilkS")
			(hide yes)
			(effects
				(font
					(size 1.27 1.27)
				)
				(justify mirror)
			)
		)
		(property "Value" ""
			(at 0 0 90)
			(layer "B.Fab")
			(effects
				(font
					(size 1.27 1.27)
				)
				(justify mirror)
			)
		)
		(duplicate_pad_numbers_are_jumpers no)
		(fp_line
			(start 0.7874 -0.4064)
			(end -0.7874 -0.4064)
			(stroke
				(width 0.1524)
				(type default)
			)
			(layer "B.SilkS")
		)
		(fp_line
			(start -0.7874 -0.4064)
			(end -0.7874 0.4064)
			(stroke
				(width 0.1524)
				(type default)
			)
			(layer "B.SilkS")
		)
		(fp_line
			(start 0.7874 0.4064)
			(end 0.7874 -0.4064)
			(stroke
				(width 0.1524)
				(type default)
			)
			(layer "B.SilkS")
		)
		(fp_line
			(start -0.7874 0.4064)
			(end 0.7874 0.4064)
			(stroke
				(width 0.1524)
				(type default)
			)
			(layer "B.SilkS")
		)
		(fp_line
			(start 0.67945 -0.305054)
			(end 0.12065 -0.305054)
			(stroke
				(width 0.1)
				(type default)
			)
			(layer "B.Fab")
		)
		(fp_line
			(start 0.12065 -0.305054)
			(end 0.12065 -0.2794)
			(stroke
				(width 0.1)
				(type default)
			)
			(layer "B.Fab")
		)
		(fp_line
			(start -0.12065 -0.3048)
			(end -0.67945 -0.3048)
			(stroke
				(width 0.1)
				(type default)
			)
			(layer "B.Fab")
		)
		(fp_line
			(start -0.67945 -0.3048)
			(end -0.67945 0.3048)
			(stroke
				(width 0.1)
				(type default)
			)
			(layer "B.Fab")
		)
		(fp_line
			(start 0.12065 -0.2794)
			(end -0.12065 -0.2794)
			(stroke
				(width 0.1)
				(type default)
			)
			(layer "B.Fab")
		)
		(fp_line
			(start -0.12065 -0.2794)
			(end -0.12065 -0.3048)
			(stroke
				(width 0.1)
				(type default)
			)
			(layer "B.Fab")
		)
		(fp_line
			(start 0.12065 0.2794)
			(end 0.12065 0.3048)
			(stroke
				(width 0.1)
				(type default)
			)
			(layer "B.Fab")
		)
		(fp_line
			(start -0.120396 0.2794)
			(end 0.12065 0.2794)
			(stroke
				(width 0.1)
				(type default)
			)
			(layer "B.Fab")
		)
		(fp_line
			(start 0.67945 0.3048)
			(end 0.67945 -0.305054)
			(stroke
				(width 0.1)
				(type default)
			)
			(layer "B.Fab")
		)
		(fp_line
			(start 0.12065 0.3048)
			(end 0.67945 0.3048)
			(stroke
				(width 0.1)
				(type default)
			)
			(layer "B.Fab")
		)
		(fp_line
			(start -0.120396 0.3048)
			(end -0.120396 0.2794)
			(stroke
				(width 0.1)
				(type default)
			)
			(layer "B.Fab")
		)
		(fp_line
			(start -0.67945 0.3048)
			(end -0.120396 0.3048)
			(stroke
				(width 0.1)
				(type default)
			)
			(layer "B.Fab")
		)
		(pad "1" smd circle
			(at 0.40005 0 270)
			(size 0 0)
			(layers "B.Cu" "B.Mask" "B.Paste")
			(net "SMB_2_BMC_GPU_SDA")
		)
		(pad "2" smd circle
			(at -0.40005 0 270)
			(size 0 0)
			(layers "B.Cu" "B.Mask" "B.Paste")
			(net "SMB_PCIE2_3V3AUX_SDA_R0")
		)
	)
)
